#ISCELL
  mstr_misc dns *
  *
#ISCELL
  pure_quanta quanta_title_block_c *
  *
#ISCELL
  pure_quanta_power bom_note *
  *
#CELL
  pure_quanta q_res *
  page271_i10
#CELL
  pure_quanta q_cap *
  page271_i11
#ISCELL
  pure_quanta_power universal_gnd *
  page271_i13
#CELL
  pure_quanta q_res *
  page271_i14
#ISCELL
  pure_quanta_power universal_gnd *
  page271_i18
#ISCELL
  pure_quanta_power universal_gnd *
  page271_i21
#CELL
  pure_quanta q_cap *
  page271_i22
#ISCELL
  pure_quanta_power universal_power *
  page271_i23
#CELL
  pure_quanta q_res *
  page271_i25
#ISCELL
  pure_quanta_power universal_power *
  page271_i26
#CELL
  pure_quanta isl28022frzt *
  page271_i28
#CELL
  pure_quanta q_res *
  page271_i29
#ISCELL
  pure_quanta_power universal_gnd *
  page271_i3
#CELL
  pure_quanta q_res *
  page271_i30
#ISCELL
  standard offpage *
  page271_i31
#ISCELL
  standard offpage *
  page271_i5
#ISCELL
  standard offpage *
  page271_i6
#CELL
  pure_quanta q_res *
  page271_i9
